#ISCELL
  mstr_misc dns *
  *
#ISCELL
  pure_quanta quanta_title_block_c *
  *
#ISCELL
  logical_power universal_power *
  page230_i10
#ISCELL
  logical_power universal_gnd *
  page230_i12
#ISCELL
  logical_power universal_gnd *
  page230_i13
#CELL
  pure_quanta q_cap *
  page230_i14
#ISCELL
  logical_power universal_power *
  page230_i15
#ISCELL
  logical_power universal_gnd *
  page230_i22
#CELL
  pure_quanta q_res *
  page230_i24
#CELL
  pure_quanta q_res *
  page230_i25
#ISCELL
  logical_power universal_power *
  page230_i26
#ISCELL
  standard offpage *
  page230_i27
#CELL
  pure_quanta q_res *
  page230_i28
#CELL
  pure_quanta q_res *
  page230_i29
#CELL
  pure_quanta q_res *
  page230_i30
#CELL
  pure_quanta 74lvc1g08w57 *
  page230_i31
#CELL
  pure_quanta q_res *
  page230_i34
#ISCELL
  standard offpage *
  page230_i35
#ISCELL
  logical_power universal_gnd *
  page230_i36
#CELL
  pure_quanta 74lvc2g07dw7 *
  page230_i37
#ISCELL
  logical_power universal_power *
  page230_i38
#ISCELL
  logical_power universal_gnd *
  page230_i39
#CELL
  pure_quanta q_cap *
  page230_i40
#CELL
  pure_quanta q_res *
  page230_i41
#ISCELL
  standard offpage *
  page230_i42
#CELL
  pure_quanta q_res *
  page230_i43
#ISCELL
  logical_power universal_gnd *
  page230_i44
#ISCELL
  standard offpage *
  page230_i45
#ISCELL
  logical_power universal_power *
  page230_i46
#CELL
  pure_quanta q_res *
  page230_i47
#CELL
  pure_quanta q_res *
  page230_i48
#ISCELL
  standard offpage *
  page230_i49
#CELL
  pure_quanta q_res *
  page230_i50
#CELL
  pure_quanta q_res *
  page230_i51
#ISCELL
  logical_power universal_power *
  page230_i52
#CELL
  pure_quanta mosfet_nch_dual *
  page230_i53
#ISCELL
  logical_power universal_gnd *
  page230_i54
#CELL
  pure_quanta q_res *
  page230_i55
#ISCELL
  logical_power universal_power *
  page230_i56
#ISCELL
  logical_power universal_gnd *
  page230_i57
#CELL
  pure_quanta mosfet_nch_dual *
  page230_i58
#CELL
  pure_quanta q_res *
  page230_i59
#ISCELL
  logical_power universal_gnd *
  page230_i6
#ISCELL
  logical_power universal_power *
  page230_i60
#ISCELL
  logical_power universal_gnd *
  page230_i61
#CELL
  pure_quanta q_cap *
  page230_i62
#ISCELL
  standard offpage *
  page230_i63
#ISCELL
  logical_power universal_gnd *
  page230_i64
#ISCELL
  standard offpage *
  page230_i7
